# BASEBOARD_FAB2 (Tioga Pass) — schematic netlist excerpt (pin names and nets, part order shuffled) for the footprints in the layout excerpt that follows; sources: Cadence DE-HDL packaged netlist, KiCad conversion of Wiwynn_Tioga_Pass_MB.brd

J6L1  SCONN288_H44441003  SCONN  pkg PIP  page 54
  \12v\(1)  = P12V_NVDIMM_DEF
  VSS(93)  = GND
  DQ(4)  = M_F_DQ<4>
  VSS(92)  = GND
  DQ(0)  = M_F_DQ<0>
  VSS(91)  = GND
  DQS9P  = M_F_DQS_DP<9>
  DQS9N  = M_F_DQS_DN<9>
  VSS(90)  = GND
  DQ(6)  = M_F_DQ<6>
  VSS(89)  = GND
  DQ(2)  = M_F_DQ<2>
  VSS(88)  = GND
  DQ(12)  = M_F_DQ<12>
  VSS(87)  = GND
  DQ(8)  = M_F_DQ<8>
  VSS(86)  = GND
  DQS10P  = M_F_DQS_DP<10>
  DQS10N  = M_F_DQS_DN<10>
  VSS(85)  = GND
  DQ(14)  = M_F_DQ<14>
  VSS(84)  = GND
  DQ(10)  = M_F_DQ<10>
  VSS(83)  = GND
  DQ(20)  = M_F_DQ<20>
  VSS(82)  = GND
  DQ(16)  = M_F_DQ<16>
  VSS(81)  = GND
  DQS11P  = M_F_DQS_DP<11>
  DQS11N  = M_F_DQS_DN<11>
  VSS(80)  = GND
  DQ(22)  = M_F_DQ<22>
  VSS(79)  = GND
  DQ(18)  = M_F_DQ<18>
  VSS(78)  = GND
  DQ(28)  = M_F_DQ<28>
  VSS(77)  = GND
  DQ(24)  = M_F_DQ<24>
  VSS(76)  = GND
  DQS12P  = M_F_DQS_DP<12>
  DQS12N  = M_F_DQS_DN<12>
  VSS(75)  = GND
  DQ(30)  = M_F_DQ<30>
  VSS(74)  = GND
  DQ(26)  = M_F_DQ<26>
  VSS(73)  = GND
  CB(4)  = M_F_ECC<4>
  VSS(72)  = GND
  CB(0)  = M_F_ECC<0>
  VSS(71)  = GND
  DQS17P  = M_F_DQS_DP<17>
  DQS17N  = M_F_DQS_DN<17>
  VSS(70)  = GND
  CB(6)  = M_F_ECC<6>
  VSS(69)  = GND
  CB(2)  = M_F_ECC<2>
  VSS(68)  = GND
  RESET_N  = M_DEF_RST_N
  VDD(25)  = PVDDQ_DEF
  CKE(0)  = M_F_CKE<2>
  VDD(24)  = PVDDQ_DEF
  ACT_N  = M_F_ACT_N
  BG(0)  = M_F_BG<0>
  VDD(23)  = PVDDQ_DEF
  A12  = M_F_MA<12>
  A9  = M_F_MA<9>
  VDD(22)  = PVDDQ_DEF
  A8  = M_F_MA<8>
  A6  = M_F_MA<6>
  VDD(21)  = PVDDQ_DEF
  A3  = M_F_MA<3>
  A1  = M_F_MA<1>
  VDD(20)  = PVDDQ_DEF
  CK0P  = M_F_CLK_DP<2>
  CK0N  = M_F_CLK_DN<2>
  VDD(19)  = PVDDQ_DEF
  VTT(1)  = PVTT_DEF
  EVENT_N  = FM_DIMM_EVENT_COD_N
  A0  = M_F_MA<0>
  VDD(18)  = PVDDQ_DEF
  BA(0)  = M_F_BA<0>
  A16_RAS_N  = M_F_MA<16>
  VDD(17)  = PVDDQ_DEF
  S0_N  = M_F_CS_N<4>
  VDD(16)  = PVDDQ_DEF
  A15_CAS_N  = M_F_MA<15>
  ODT(0)  = M_F_ODT<2>
  VDD(15)  = PVDDQ_DEF
  S1_N  = M_F_CS_N<5>
  VDD(14)  = PVDDQ_DEF
  ODT(1)  = M_F_ODT<3>
  VDD(13)  = PVDDQ_DEF
  S2_N_C(0)  = M_F_CS_N<6>
  VSS(67)  = GND
  DQ(36)  = M_F_DQ<36>
  VSS(66)  = GND
  DQ(32)  = M_F_DQ<32>
  VSS(65)  = GND
  DQS13P  = M_F_DQS_DP<13>
  DQS13N  = M_F_DQS_DN<13>
  VSS(64)  = GND
  DQ(38)  = M_F_DQ<38>
  VSS(63)  = GND
  DQ(34)  = M_F_DQ<34>
  VSS(62)  = GND
  DQ(44)  = M_F_DQ<44>
  VSS(61)  = GND
  DQ(40)  = M_F_DQ<40>
  VSS(60)  = GND
  DQS14P  = M_F_DQS_DP<14>
  DQS14N  = M_F_DQS_DN<14>
  VSS(59)  = GND
  DQ(46)  = M_F_DQ<46>
  VSS(58)  = GND
  DQ(42)  = M_F_DQ<42>
  VSS(57)  = GND
  DQ(52)  = M_F_DQ<52>
  VSS(56)  = GND
  DQ(48)  = M_F_DQ<48>
  VSS(55)  = GND
  DQS15P  = M_F_DQS_DP<15>
  DQS15N  = M_F_DQS_DN<15>
  VSS(54)  = GND
  DQ(54)  = M_F_DQ<54>
  VSS(53)  = GND
  DQ(50)  = M_F_DQ<50>
  VSS(52)  = GND
  DQ(60)  = M_F_DQ<60>
  VSS(51)  = GND
  DQ(56)  = M_F_DQ<56>
  VSS(50)  = GND
  DQS16P  = M_F_DQS_DP<16>
  DQS16N  = M_F_DQS_DN<16>
  VSS(49)  = GND
  DQ(62)  = M_F_DQ<62>
  VSS(48)  = GND
  DQ(58)  = M_F_DQ<58>
  VSS(47)  = GND
  SA(0)  = PVPP_DEF
  SA(1)  = GND
  SCL  = SMB_DDR_DEF_VPP_SCL
  VPP(4)  = PVPP_DEF
  VPP(3)  = PVPP_DEF
  RFU(2)  = TP_CH_F_DIMM_F1_RFU_2
  \12v\(0)  = P12V_NVDIMM_DEF
  VREFCA  = M_F_VREF
  VSS(46)  = GND
  DQ(5)  = M_F_DQ<5>
  VSS(45)  = GND
  DQ(1)  = M_F_DQ<1>
  VSS(44)  = GND
  DQS0N  = M_F_DQS_DN<0>
  DQS0P  = M_F_DQS_DP<0>
  VSS(43)  = GND
  DQ(7)  = M_F_DQ<7>
  VSS(42)  = GND
  DQ(3)  = M_F_DQ<3>
  VSS(41)  = GND
  DQ(13)  = M_F_DQ<13>
  VSS(40)  = GND
  DQ(9)  = M_F_DQ<9>
  VSS(39)  = GND
  DQS1N  = M_F_DQS_DN<1>
  DQS1P  = M_F_DQS_DP<1>
  VSS(38)  = GND
  DQ(15)  = M_F_DQ<15>
  VSS(37)  = GND
  DQ(11)  = M_F_DQ<11>
  VSS(36)  = GND
  DQ(21)  = M_F_DQ<21>
  VSS(35)  = GND
  DQ(17)  = M_F_DQ<17>
  VSS(34)  = GND
  DQS2N  = M_F_DQS_DN<2>
  DQS2P  = M_F_DQS_DP<2>
  VSS(33)  = GND
  DQ(23)  = M_F_DQ<23>
  VSS(32)  = GND
  DQ(19)  = M_F_DQ<19>
  VSS(31)  = GND
  DQ(29)  = M_F_DQ<29>
  VSS(30)  = GND
  DQ(25)  = M_F_DQ<25>
  VSS(29)  = GND
  DQS3N  = M_F_DQS_DN<3>
  DQS3P  = M_F_DQS_DP<3>
  VSS(28)  = GND
  DQ(31)  = M_F_DQ<31>
  VSS(27)  = GND
  DQ(27)  = M_F_DQ<27>
  VSS(26)  = GND
  CB(5)  = M_F_ECC<5>
  VSS(25)  = GND
  CB(1)  = M_F_ECC<1>
  VSS(24)  = GND
  DQS8N  = M_F_DQS_DN<8>
  DQS8P  = M_F_DQS_DP<8>
  VSS(23)  = GND
  CB(7)  = M_F_ECC<7>
  VSS(22)  = GND
  CB(3)  = M_F_ECC<3>
  VSS(21)  = GND
  CKE(1)  = M_F_CKE<3>
  VDD(12)  = PVDDQ_DEF
  RFU(0)  = TP_CH_F_DIMM_F1_RFU_0
  VDD(11)  = PVDDQ_DEF
  BG(1)  = M_F_BG<1>
  ALERT_N  = M_F_ALERT_N
  VDD(10)  = PVDDQ_DEF
  A11  = M_F_MA<11>
  A7  = M_F_MA<7>
  VDD(9)  = PVDDQ_DEF
  A5  = M_F_MA<5>
  A4  = M_F_MA<4>
  VDD(8)  = PVDDQ_DEF
  A2  = M_F_MA<2>
  VDD(7)  = PVDDQ_DEF
  CK1P  = M_F_CLK_DP<3>
  CK1N  = M_F_CLK_DN<3>
  VDD(6)  = PVDDQ_DEF
  VTT(0)  = PVTT_DEF
  PAR  = M_F_PAR
  VDD(5)  = PVDDQ_DEF
  BA(1)  = M_F_BA<1>
  A10  = M_F_MA<10>
  VDD(4)  = PVDDQ_DEF
  RFU(1)  = TP_CH_F_DIMM_F1_RFU_1
  A14_WE_N  = M_F_MA<14>
  VDD(3)  = PVDDQ_DEF
  SAVE_N_NC  = FM_ADR_COMPLETE_DEF_N
  VDD(2)  = PVDDQ_DEF
  A13  = M_F_MA<13>
  VDD(1)  = PVDDQ_DEF
  A17  = M_F_MA<17>
  C(2)  = M_F_C<2>
  VDD(0)  = PVDDQ_DEF
  S3_N_C(1)  = M_F_CS_N<7>
  SA(2)  = PVPP_DEF
  VSS(20)  = GND
  DQ(37)  = M_F_DQ<37>
  VSS(19)  = GND
  DQ(33)  = M_F_DQ<33>
  VSS(18)  = GND
  DQS4N  = M_F_DQS_DN<4>
  DQS4P  = M_F_DQS_DP<4>
  VSS(17)  = GND
  DQ(39)  = M_F_DQ<39>
  VSS(16)  = GND
  DQ(35)  = M_F_DQ<35>
  VSS(15)  = GND
  DQ(45)  = M_F_DQ<45>
  VSS(14)  = GND
  DQ(41)  = M_F_DQ<41>
  VSS(13)  = GND
  DQS5N  = M_F_DQS_DN<5>
  DQS5P  = M_F_DQS_DP<5>
  VSS(12)  = GND
  DQ(47)  = M_F_DQ<47>
  VSS(11)  = GND
  DQ(43)  = M_F_DQ<43>
  VSS(10)  = GND
  DQ(53)  = M_F_DQ<53>
  VSS(9)  = GND
  DQ(49)  = M_F_DQ<49>
  VSS(8)  = GND
  DQS6N  = M_F_DQS_DN<6>
  DQS6P  = M_F_DQS_DP<6>
  VSS(7)  = GND
  DQ(55)  = M_F_DQ<55>
  VSS(6)  = GND
  DQ(51)  = M_F_DQ<51>
  VSS(5)  = GND
  DQ(61)  = M_F_DQ<61>
  VSS(4)  = GND
  DQ(57)  = M_F_DQ<57>
  VSS(3)  = GND
  DQS7N  = M_F_DQS_DN<7>
  DQS7P  = M_F_DQS_DP<7>
  VSS(2)  = GND
  DQ(63)  = M_F_DQ<63>
  VSS(1)  = GND
  DQ(59)  = M_F_DQ<59>
  VSS(0)  = GND
  VDDSPD  = PVPP_DEF
  SDA  = SMB_DDR_DEF_VPP_SDA
  VPP(1)  = PVPP_DEF
  VPP(0)  = PVPP_DEF
  VPP(2)  = PVPP_DEF

(kicad_pcb
	(version 20260206)
	(generator "pcbnew")
	(generator_version "10.0")
	(general
		(thickness 1.6)
		(legacy_teardrops no)
	)
	(paper "A4")
	(title_block
		(title "Wiwynn_Tioga_Pass_MB.brd")
		(comment 1 "Tioga Pass / footprint 4129 of 4770 (J6L1), pads 101-151 of 291")
	)
	(layers
		(0 "F.Cu" signal "TOP")
		(4 "In1.Cu" signal "L2GND")
		(6 "In2.Cu" signal "L3")
		(8 "In3.Cu" signal "L4GND")
		(10 "In4.Cu" signal "L5")
		(12 "In5.Cu" signal "L6GND")
		(14 "In6.Cu" signal "L7VCC")
		(16 "In7.Cu" signal "L8VCC")
		(18 "In8.Cu" signal "L9GND")
		(20 "In9.Cu" signal "L10")
		(22 "In10.Cu" signal "L11GND")
		(24 "In11.Cu" signal "L12")
		(26 "In12.Cu" signal "L13GND")
		(2 "B.Cu" signal "BOTTOM")
		(9 "F.Adhes" user "F.Adhesive")
		(11 "B.Adhes" user "B.Adhesive")
		(13 "F.Paste" user "Package Geometry/Pastemask Top")
		(15 "B.Paste" user "Package Geometry/Pastemask Bottom")
		(5 "F.SilkS" user "Ref Des/Silkscreen Top")
		(7 "B.SilkS" user "Ref Des/Silkscreen Bottom")
		(1 "F.Mask" user "Board Geometry/Soldermask Top")
		(3 "B.Mask" user "Board Geometry/Soldermask Bottom")
		(17 "Dwgs.User" user "User.Drawings")
		(19 "Cmts.User" user "User.Comments")
		(21 "Eco1.User" user "User.Eco1")
		(23 "Eco2.User" user "User.Eco2")
		(25 "Edge.Cuts" user "Board Geometry/Outline")
		(27 "Margin" user)
		(31 "F.CrtYd" user "Package Geometry/Place Bound Top")
		(29 "B.CrtYd" user "Package Geometry/Place Bound Bottom")
		(35 "F.Fab" user "Ref Des/Assembly Top")
		(33 "B.Fab" user "Ref Des/Assembly Bottom")
	)
	(footprint ""
		(layer "B.Cu")
		(at 194.700398 -152.078436 90)
		(property "Reference" "J6L1"
			(at 2.200148 37.96411 0)
			(unlocked yes)
			(layer "B.SilkS")
			(effects
				(font
					(size 0.7874 0.5842)
					(thickness 0.1524)
				)
				(justify left mirror)
			)
		)
		(property "Value" ""
			(at 0 0 90)
			(layer "B.Fab")
			(effects
				(font
					(size 1.27 1.27)
				)
				(justify mirror)
			)
		)
		(duplicate_pad_numbers_are_jumpers no)
		(pad "98" smd rect
			(at 0 87.54999 270)
			(size 1.8034 0.508)
			(layers "B.Cu" "B.Mask" "B.Paste")
			(net "GND")
		)
		(pad "99" smd rect
			(at 0 88.399874 270)
			(size 1.8034 0.508)
			(layers "B.Cu" "B.Mask" "B.Paste")
			(net "M_F_DQS_DP<13>")
		)
		(pad "100" smd rect
			(at 0 89.250012 270)
			(size 1.8034 0.508)
			(layers "B.Cu" "B.Mask" "B.Paste")
			(net "M_F_DQS_DN<13>")
		)
		(pad "101" smd rect
			(at 0 90.099896 270)
			(size 1.8034 0.508)
			(layers "B.Cu" "B.Mask" "B.Paste")
			(net "GND")
		)
		(pad "102" smd rect
			(at 0 90.950034 270)
			(size 1.8034 0.508)
			(layers "B.Cu" "B.Mask" "B.Paste")
			(net "M_F_DQ<38>")
		)
		(pad "103" smd rect
			(at 0 91.799918 270)
			(size 1.8034 0.508)
			(layers "B.Cu" "B.Mask" "B.Paste")
			(net "GND")
		)
		(pad "104" smd rect
			(at 0 92.650056 270)
			(size 1.8034 0.508)
			(layers "B.Cu" "B.Mask" "B.Paste")
			(net "M_F_DQ<34>")
		)
		(pad "105" smd rect
			(at 0 93.49994 270)
			(size 1.8034 0.508)
			(layers "B.Cu" "B.Mask" "B.Paste")
			(net "GND")
		)
		(pad "106" smd rect
			(at 0 94.350078 270)
			(size 1.8034 0.508)
			(layers "B.Cu" "B.Mask" "B.Paste")
			(net "M_F_DQ<44>")
		)
		(pad "107" smd rect
			(at 0 95.199962 270)
			(size 1.8034 0.508)
			(layers "B.Cu" "B.Mask" "B.Paste")
			(net "GND")
		)
		(pad "108" smd rect
			(at 0 96.0501 270)
			(size 1.8034 0.508)
			(layers "B.Cu" "B.Mask" "B.Paste")
			(net "M_F_DQ<40>")
		)
		(pad "109" smd rect
			(at 0 96.899984 270)
			(size 1.8034 0.508)
			(layers "B.Cu" "B.Mask" "B.Paste")
			(net "GND")
		)
		(pad "110" smd rect
			(at 0 97.750122 270)
			(size 1.8034 0.508)
			(layers "B.Cu" "B.Mask" "B.Paste")
			(net "M_F_DQS_DP<14>")
		)
		(pad "111" smd rect
			(at 0 98.600006 270)
			(size 1.8034 0.508)
			(layers "B.Cu" "B.Mask" "B.Paste")
			(net "M_F_DQS_DN<14>")
		)
		(pad "112" smd rect
			(at 0 99.44989 270)
			(size 1.8034 0.508)
			(layers "B.Cu" "B.Mask" "B.Paste")
			(net "GND")
		)
		(pad "113" smd rect
			(at 0 100.300028 270)
			(size 1.8034 0.508)
			(layers "B.Cu" "B.Mask" "B.Paste")
			(net "M_F_DQ<46>")
		)
		(pad "114" smd rect
			(at 0 101.149912 270)
			(size 1.8034 0.508)
			(layers "B.Cu" "B.Mask" "B.Paste")
			(net "GND")
		)
		(pad "115" smd rect
			(at 0 102.00005 270)
			(size 1.8034 0.508)
			(layers "B.Cu" "B.Mask" "B.Paste")
			(net "M_F_DQ<42>")
		)
		(pad "116" smd rect
			(at 0 102.849934 270)
			(size 1.8034 0.508)
			(layers "B.Cu" "B.Mask" "B.Paste")
			(net "GND")
		)
		(pad "117" smd rect
			(at 0 103.700072 270)
			(size 1.8034 0.508)
			(layers "B.Cu" "B.Mask" "B.Paste")
			(net "M_F_DQ<52>")
		)
		(pad "118" smd rect
			(at 0 104.549956 270)
			(size 1.8034 0.508)
			(layers "B.Cu" "B.Mask" "B.Paste")
			(net "GND")
		)
		(pad "119" smd rect
			(at 0 105.400094 270)
			(size 1.8034 0.508)
			(layers "B.Cu" "B.Mask" "B.Paste")
			(net "M_F_DQ<48>")
		)
		(pad "120" smd rect
			(at 0 106.249978 270)
			(size 1.8034 0.508)
			(layers "B.Cu" "B.Mask" "B.Paste")
			(net "GND")
		)
		(pad "121" smd rect
			(at 0 107.100116 270)
			(size 1.8034 0.508)
			(layers "B.Cu" "B.Mask" "B.Paste")
			(net "M_F_DQS_DP<15>")
		)
		(pad "122" smd rect
			(at 0 107.95 270)
			(size 1.8034 0.508)
			(layers "B.Cu" "B.Mask" "B.Paste")
			(net "M_F_DQS_DN<15>")
		)
		(pad "123" smd rect
			(at 0 108.799884 270)
			(size 1.8034 0.508)
			(layers "B.Cu" "B.Mask" "B.Paste")
			(net "GND")
		)
		(pad "124" smd rect
			(at 0 109.650022 270)
			(size 1.8034 0.508)
			(layers "B.Cu" "B.Mask" "B.Paste")
			(net "M_F_DQ<54>")
		)
		(pad "125" smd rect
			(at 0 110.499906 270)
			(size 1.8034 0.508)
			(layers "B.Cu" "B.Mask" "B.Paste")
			(net "GND")
		)
		(pad "126" smd rect
			(at 0 111.350044 270)
			(size 1.8034 0.508)
			(layers "B.Cu" "B.Mask" "B.Paste")
			(net "M_F_DQ<50>")
		)
		(pad "127" smd rect
			(at 0 112.199928 270)
			(size 1.8034 0.508)
			(layers "B.Cu" "B.Mask" "B.Paste")
			(net "GND")
		)
		(pad "128" smd rect
			(at 0 113.050066 270)
			(size 1.8034 0.508)
			(layers "B.Cu" "B.Mask" "B.Paste")
			(net "M_F_DQ<60>")
		)
		(pad "129" smd rect
			(at 0 113.89995 270)
			(size 1.8034 0.508)
			(layers "B.Cu" "B.Mask" "B.Paste")
			(net "GND")
		)
		(pad "130" smd rect
			(at 0 114.750088 270)
			(size 1.8034 0.508)
			(layers "B.Cu" "B.Mask" "B.Paste")
			(net "M_F_DQ<56>")
		)
		(pad "131" smd rect
			(at 0 115.599972 270)
			(size 1.8034 0.508)
			(layers "B.Cu" "B.Mask" "B.Paste")
			(net "GND")
		)
		(pad "132" smd rect
			(at 0 116.45011 270)
			(size 1.8034 0.508)
			(layers "B.Cu" "B.Mask" "B.Paste")
			(net "M_F_DQS_DP<16>")
		)
		(pad "133" smd rect
			(at 0 117.299994 270)
			(size 1.8034 0.508)
			(layers "B.Cu" "B.Mask" "B.Paste")
			(net "M_F_DQS_DN<16>")
		)
		(pad "134" smd rect
			(at 0 118.149878 270)
			(size 1.8034 0.508)
			(layers "B.Cu" "B.Mask" "B.Paste")
			(net "GND")
		)
		(pad "135" smd rect
			(at 0 119.000016 270)
			(size 1.8034 0.508)
			(layers "B.Cu" "B.Mask" "B.Paste")
			(net "M_F_DQ<62>")
		)
		(pad "136" smd rect
			(at 0 119.8499 270)
			(size 1.8034 0.508)
			(layers "B.Cu" "B.Mask" "B.Paste")
			(net "GND")
		)
		(pad "137" smd rect
			(at 0 120.700038 270)
			(size 1.8034 0.508)
			(layers "B.Cu" "B.Mask" "B.Paste")
			(net "M_F_DQ<58>")
		)
		(pad "138" smd rect
			(at 0 121.549922 270)
			(size 1.8034 0.508)
			(layers "B.Cu" "B.Mask" "B.Paste")
			(net "GND")
		)
		(pad "139" smd rect
			(at 0 122.40006 270)
			(size 1.8034 0.508)
			(layers "B.Cu" "B.Mask" "B.Paste")
			(net "PVPP_DEF")
		)
		(pad "140" smd rect
			(at 0 123.249944 270)
			(size 1.8034 0.508)
			(layers "B.Cu" "B.Mask" "B.Paste")
			(net "GND")
		)
		(pad "141" smd rect
			(at 0 124.100082 270)
			(size 1.8034 0.508)
			(layers "B.Cu" "B.Mask" "B.Paste")
			(net "SMB_DDR_DEF_VPP_SCL")
		)
		(pad "142" smd rect
			(at 0 124.949966 270)
			(size 1.8034 0.508)
			(layers "B.Cu" "B.Mask" "B.Paste")
			(net "PVPP_DEF")
		)
		(pad "143" smd rect
			(at 0 125.800104 270)
			(size 1.8034 0.508)
			(layers "B.Cu" "B.Mask" "B.Paste")
			(net "PVPP_DEF")
		)
		(pad "144" smd rect
			(at 0 126.649988 270)
			(size 1.8034 0.508)
			(layers "B.Cu" "B.Mask" "B.Paste")
			(net "TP_CH_F_DIMM_F1_RFU_2")
		)
		(pad "145" smd rect
			(at -4.59994 0 270)
			(size 1.8034 0.508)
			(layers "B.Cu" "B.Mask" "B.Paste")
			(net "P12V_NVDIMM_DEF")
		)
		(pad "146" smd rect
			(at -4.59994 0.849884 270)
			(size 1.8034 0.508)
			(layers "B.Cu" "B.Mask" "B.Paste")
			(net "M_F_VREF")
		)
		(pad "147" smd rect
			(at -4.59994 1.700022 270)
			(size 1.8034 0.508)
			(layers "B.Cu" "B.Mask" "B.Paste")
			(net "GND")
		)
		(pad "148" smd rect
			(at -4.59994 2.549906 270)
			(size 1.8034 0.508)
			(layers "B.Cu" "B.Mask" "B.Paste")
			(net "M_F_DQ<5>")
		)
	)
)
